# S9S_MB_2U (Grand Teton) — schematic netlist excerpt (pin names and nets, part order shuffled) for the footprints in the layout excerpt that follows; sources: Cadence DE-HDL packaged netlist, KiCad conversion of 03242023_DA0F0TMBIJ0_F0T_Motherboard_J_brd_V01_OCP.brd

R1307  Q_RES  33.2 1% CHIP  pkg 0402LF  page 205 : A = FM_THROTTLE_N ; B = FM_THROTTLE_R_N
PC292  Q_CAP  2.2UF 10V 10% X6S  pkg C0402  page 267 : A = PVCCIN_CPU0_VDD2 ; B = GND

(kicad_pcb
	(version 20260206)
	(generator "pcbnew")
	(generator_version "10.0")
	(general
		(thickness 1.6)
		(legacy_teardrops no)
	)
	(paper "A4")
	(title_block
		(title "03242023_DA0F0TMBIJ0_F0T_Motherboard_J_brd_V01_OCP.brd")
		(comment 1 "Grand Teton / footprints 867-868 of 6105")
	)
	(layers
		(0 "F.Cu" signal "TOP")
		(4 "In1.Cu" signal "GND")
		(6 "In2.Cu" signal "IN1")
		(8 "In3.Cu" signal "GND1")
		(10 "In4.Cu" signal "IN2")
		(12 "In5.Cu" signal "GND2")
		(14 "In6.Cu" signal "IN3")
		(16 "In7.Cu" signal "GND3")
		(18 "In8.Cu" signal "VCC")
		(20 "In9.Cu" signal "VCC1")
		(22 "In10.Cu" signal "GND4")
		(24 "In11.Cu" signal "IN4")
		(26 "In12.Cu" signal "GND5")
		(28 "In13.Cu" signal "IN5")
		(30 "In14.Cu" signal "GND6")
		(32 "In15.Cu" signal "IN6")
		(34 "In16.Cu" signal "GND7")
		(2 "B.Cu" signal "BOTTOM")
		(9 "F.Adhes" user "F.Adhesive")
		(11 "B.Adhes" user "B.Adhesive")
		(13 "F.Paste" user "Package Geometry/Pastemask Top")
		(15 "B.Paste" user "Package Geometry/Pastemask Bottom")
		(5 "F.SilkS" user "Ref Des/Silkscreen Top")
		(7 "B.SilkS" user "Ref Des/Silkscreen Bottom")
		(1 "F.Mask" user "Board Geometry/Soldermask Top")
		(3 "B.Mask" user "Board Geometry/Soldermask Bottom")
		(17 "Dwgs.User" user "User.Drawings")
		(19 "Cmts.User" user "User.Comments")
		(21 "Eco1.User" user "User.Eco1")
		(23 "Eco2.User" user "User.Eco2")
		(25 "Edge.Cuts" user "Board Geometry/Outline")
		(27 "Margin" user)
		(31 "F.CrtYd" user "Package Geometry/Place Bound Top")
		(29 "B.CrtYd" user "Package Geometry/Place Bound Bottom")
		(35 "F.Fab" user "Ref Des/Assembly Top")
		(33 "B.Fab" user "Ref Des/Assembly Bottom")
	)
	(footprint ""
		(layer "F.Cu")
		(at 349.523304 -336.192368 90)
		(property "Reference" "PC292"
			(at 0 0 90)
			(layer "F.SilkS")
			(hide yes)
			(effects
				(font
					(size 1.27 1.27)
				)
			)
		)
		(property "Value" ""
			(at 0 0 90)
			(layer "F.Fab")
			(effects
				(font
					(size 1.27 1.27)
				)
			)
		)
		(duplicate_pad_numbers_are_jumpers no)
		(fp_line
			(start 0.7874 -0.4064)
			(end 0.7874 0.4064)
			(stroke
				(width 0.1524)
				(type default)
			)
			(layer "F.SilkS")
		)
		(fp_line
			(start -0.7874 -0.4064)
			(end 0.7874 -0.4064)
			(stroke
				(width 0.1524)
				(type default)
			)
			(layer "F.SilkS")
		)
		(fp_line
			(start 0.7874 0.4064)
			(end -0.7874 0.4064)
			(stroke
				(width 0.1524)
				(type default)
			)
			(layer "F.SilkS")
		)
		(fp_line
			(start -0.7874 0.4064)
			(end -0.7874 -0.4064)
			(stroke
				(width 0.1524)
				(type default)
			)
			(layer "F.SilkS")
		)
		(fp_line
			(start -0.12065 -0.305054)
			(end -0.12065 -0.2794)
			(stroke
				(width 0.1)
				(type default)
			)
			(layer "F.Fab")
		)
		(fp_line
			(start -0.67945 -0.305054)
			(end -0.12065 -0.305054)
			(stroke
				(width 0.1)
				(type default)
			)
			(layer "F.Fab")
		)
		(fp_line
			(start 0.67945 -0.3048)
			(end 0.67945 0.3048)
			(stroke
				(width 0.1)
				(type default)
			)
			(layer "F.Fab")
		)
		(fp_line
			(start 0.12065 -0.3048)
			(end 0.67945 -0.3048)
			(stroke
				(width 0.1)
				(type default)
			)
			(layer "F.Fab")
		)
		(fp_line
			(start 0.12065 -0.2794)
			(end 0.12065 -0.3048)
			(stroke
				(width 0.1)
				(type default)
			)
			(layer "F.Fab")
		)
		(fp_line
			(start -0.12065 -0.2794)
			(end 0.12065 -0.2794)
			(stroke
				(width 0.1)
				(type default)
			)
			(layer "F.Fab")
		)
		(fp_line
			(start 0.120396 0.2794)
			(end -0.12065 0.2794)
			(stroke
				(width 0.1)
				(type default)
			)
			(layer "F.Fab")
		)
		(fp_line
			(start -0.12065 0.2794)
			(end -0.12065 0.3048)
			(stroke
				(width 0.1)
				(type default)
			)
			(layer "F.Fab")
		)
		(fp_line
			(start 0.67945 0.3048)
			(end 0.120396 0.3048)
			(stroke
				(width 0.1)
				(type default)
			)
			(layer "F.Fab")
		)
		(fp_line
			(start 0.120396 0.3048)
			(end 0.120396 0.2794)
			(stroke
				(width 0.1)
				(type default)
			)
			(layer "F.Fab")
		)
		(fp_line
			(start -0.12065 0.3048)
			(end -0.67945 0.3048)
			(stroke
				(width 0.1)
				(type default)
			)
			(layer "F.Fab")
		)
		(fp_line
			(start -0.67945 0.3048)
			(end -0.67945 -0.305054)
			(stroke
				(width 0.1)
				(type default)
			)
			(layer "F.Fab")
		)
		(pad "1" smd circle
			(at -0.40005 0 90)
			(size 0 0)
			(layers "F.Cu" "F.Mask" "F.Paste")
			(net "PVCCIN_CPU0_VDD2")
		)
		(pad "2" smd circle
			(at 0.40005 0 90)
			(size 0 0)
			(layers "F.Cu" "F.Mask" "F.Paste")
			(net "GND")
		)
	)
	(footprint ""
		(layer "F.Cu")
		(at 307.899308 -30.255718 -90)
		(property "Reference" "R1307"
			(at 0 0 270)
			(layer "F.SilkS")
			(hide yes)
			(effects
				(font
					(size 1.27 1.27)
				)
			)
		)
		(property "Value" ""
			(at 0 0 270)
			(layer "F.Fab")
			(effects
				(font
					(size 1.27 1.27)
				)
			)
		)
		(duplicate_pad_numbers_are_jumpers no)
		(fp_line
			(start -0.7874 0.4064)
			(end -0.7874 -0.4064)
			(stroke
				(width 0.1524)
				(type default)
			)
			(layer "F.SilkS")
		)
		(fp_line
			(start 0.7874 0.4064)
			(end -0.7874 0.4064)
			(stroke
				(width 0.1524)
				(type default)
			)
			(layer "F.SilkS")
		)
		(fp_line
			(start -0.7874 -0.4064)
			(end 0.7874 -0.4064)
			(stroke
				(width 0.1524)
				(type default)
			)
			(layer "F.SilkS")
		)
		(fp_line
			(start 0.7874 -0.4064)
			(end 0.7874 0.4064)
			(stroke
				(width 0.1524)
				(type default)
			)
			(layer "F.SilkS")
		)
		(fp_line
			(start -0.67945 0.3048)
			(end -0.67945 -0.305054)
			(stroke
				(width 0.1)
				(type default)
			)
			(layer "F.Fab")
		)
		(fp_line
			(start -0.12065 0.3048)
			(end -0.67945 0.3048)
			(stroke
				(width 0.1)
				(type default)
			)
			(layer "F.Fab")
		)
		(fp_line
			(start 0.120396 0.3048)
			(end 0.120396 0.2794)
			(stroke
				(width 0.1)
				(type default)
			)
			(layer "F.Fab")
		)
		(fp_line
			(start 0.67945 0.3048)
			(end 0.120396 0.3048)
			(stroke
				(width 0.1)
				(type default)
			)
			(layer "F.Fab")
		)
		(fp_line
			(start -0.12065 0.2794)
			(end -0.12065 0.3048)
			(stroke
				(width 0.1)
				(type default)
			)
			(layer "F.Fab")
		)
		(fp_line
			(start 0.120396 0.2794)
			(end -0.12065 0.2794)
			(stroke
				(width 0.1)
				(type default)
			)
			(layer "F.Fab")
		)
		(fp_line
			(start -0.12065 -0.2794)
			(end 0.12065 -0.2794)
			(stroke
				(width 0.1)
				(type default)
			)
			(layer "F.Fab")
		)
		(fp_line
			(start 0.12065 -0.2794)
			(end 0.12065 -0.3048)
			(stroke
				(width 0.1)
				(type default)
			)
			(layer "F.Fab")
		)
		(fp_line
			(start 0.12065 -0.3048)
			(end 0.67945 -0.3048)
			(stroke
				(width 0.1)
				(type default)
			)
			(layer "F.Fab")
		)
		(fp_line
			(start 0.67945 -0.3048)
			(end 0.67945 0.3048)
			(stroke
				(width 0.1)
				(type default)
			)
			(layer "F.Fab")
		)
		(fp_line
			(start -0.67945 -0.305054)
			(end -0.12065 -0.305054)
			(stroke
				(width 0.1)
				(type default)
			)
			(layer "F.Fab")
		)
		(fp_line
			(start -0.12065 -0.305054)
			(end -0.12065 -0.2794)
			(stroke
				(width 0.1)
				(type default)
			)
			(layer "F.Fab")
		)
		(pad "1" smd circle
			(at -0.40005 0 270)
			(size 0 0)
			(layers "F.Cu" "F.Mask" "F.Paste")
			(net "FM_THROTTLE_N")
		)
		(pad "2" smd circle
			(at 0.40005 0 270)
			(size 0 0)
			(layers "F.Cu" "F.Mask" "F.Paste")
			(net "FM_THROTTLE_R_N")
		)
	)
)
